(kicad_pcb
	(version 20260206)
	(generator "pcbnew")
	(generator_version "10.0")
	(general
		(thickness 1.6)
		(legacy_teardrops no)
	)
	(paper "A4")
	(title_block
		(title "Wiwynn_Tioga_Pass_MB.brd")
		(comment 1 "Tioga Pass / footprints 1090-1096 of 4770")
	)
	(layers
		(0 "F.Cu" signal "TOP")
		(4 "In1.Cu" signal "L2GND")
		(6 "In2.Cu" signal "L3")
		(8 "In3.Cu" signal "L4GND")
		(10 "In4.Cu" signal "L5")
		(12 "In5.Cu" signal "L6GND")
		(14 "In6.Cu" signal "L7VCC")
		(16 "In7.Cu" signal "L8VCC")
		(18 "In8.Cu" signal "L9GND")
		(20 "In9.Cu" signal "L10")
		(22 "In10.Cu" signal "L11GND")
		(24 "In11.Cu" signal "L12")
		(26 "In12.Cu" signal "L13GND")
		(2 "B.Cu" signal "BOTTOM")
		(9 "F.Adhes" user "F.Adhesive")
		(11 "B.Adhes" user "B.Adhesive")
		(13 "F.Paste" user "Package Geometry/Pastemask Top")
		(15 "B.Paste" user "Package Geometry/Pastemask Bottom")
		(5 "F.SilkS" user "Ref Des/Silkscreen Top")
		(7 "B.SilkS" user "Ref Des/Silkscreen Bottom")
		(1 "F.Mask" user "Board Geometry/Soldermask Top")
		(3 "B.Mask" user "Board Geometry/Soldermask Bottom")
		(17 "Dwgs.User" user "User.Drawings")
		(19 "Cmts.User" user "User.Comments")
		(21 "Eco1.User" user "User.Eco1")
		(23 "Eco2.User" user "User.Eco2")
		(25 "Edge.Cuts" user "Board Geometry/Outline")
		(27 "Margin" user)
		(31 "F.CrtYd" user "Package Geometry/Place Bound Top")
		(29 "B.CrtYd" user "Package Geometry/Place Bound Bottom")
		(35 "F.Fab" user "Ref Des/Assembly Top")
		(33 "B.Fab" user "Ref Des/Assembly Bottom")
	)
	(footprint ""
		(layer "F.Cu")
		(at 458.177392 -40.877998 -90)
		(property "Reference" "C9F4"
			(at 0 0 270)
			(layer "F.SilkS")
			(hide yes)
			(effects
				(font
					(size 1.27 1.27)
				)
			)
		)
		(property "Value" ""
			(at 0 0 270)
			(layer "F.Fab")
			(effects
				(font
					(size 1.27 1.27)
				)
			)
		)
		(duplicate_pad_numbers_are_jumpers no)
		(fp_poly
			(pts
				(xy -0.7239 -0.2159) (xy 0.7239 -0.2159) (xy 0.7239 1.9939) (xy -0.7239 1.9939)
			)
			(stroke
				(width 0)
				(type default)
			)
			(fill no)
			(layer "F.CrtYd")
		)
		(fp_line
			(start -0.7239 1.9939)
			(end 0.7239 1.9939)
			(stroke
				(width 0.1)
				(type default)
			)
			(layer "F.Fab")
		)
		(fp_line
			(start 0.7239 1.9939)
			(end 0.7239 -0.2159)
			(stroke
				(width 0.1)
				(type default)
			)
			(layer "F.Fab")
		)
		(fp_line
			(start -0.7239 -0.2159)
			(end -0.7239 1.9939)
			(stroke
				(width 0.1)
				(type default)
			)
			(layer "F.Fab")
		)
		(fp_line
			(start 0.7239 -0.2159)
			(end -0.7239 -0.2159)
			(stroke
				(width 0.1)
				(type default)
			)
			(layer "F.Fab")
		)
		(pad "1" smd rect
			(at 0 0 270)
			(size 1.27 1.016)
			(layers "F.Cu" "F.Mask" "F.Paste")
			(net "P1V15_AUX_BMC")
		)
		(pad "2" smd rect
			(at 0 1.778 270)
			(size 1.27 1.016)
			(layers "F.Cu" "F.Mask" "F.Paste")
			(net "GND")
		)
		(zone
			(layer "F.Cu")
			(hatch none 0.5)
			(connect_pads
				(clearance 0)
			)
			(min_thickness 0.25)
			(keepout
				(tracks not_allowed)
				(vias allowed)
				(pads allowed)
				(copperpour not_allowed)
				(footprints allowed)
			)
			(placement
				(enabled no)
				(sheetname "")
			)
			(fill
				(thermal_gap 0.5)
				(thermal_bridge_width 0.5)
				(island_removal_mode 0)
			)
			(polygon
				(pts
					(xy 457.669392 -41.512998) (xy 457.669392 -40.242998) (xy 456.907392 -40.242998) (xy 456.907392 -41.512998)
				)
			)
		)
	)
	(footprint ""
		(layer "F.Cu")
		(at 179.959 -130.8735 180)
		(property "Reference" "R4B10"
			(at 0 0 180)
			(layer "F.SilkS")
			(hide yes)
			(effects
				(font
					(size 1.27 1.27)
				)
			)
		)
		(property "Value" ""
			(at 0 0 180)
			(layer "F.Fab")
			(effects
				(font
					(size 1.27 1.27)
				)
			)
		)
		(duplicate_pad_numbers_are_jumpers no)
		(fp_poly
			(pts
				(xy -0.2794 -0.1016) (xy 0.2794 -0.1016) (xy 0.2794 0.9906) (xy -0.2794 0.9906)
			)
			(stroke
				(width 0)
				(type default)
			)
			(fill no)
			(layer "F.CrtYd")
		)
		(fp_line
			(start 0.2794 0.9906)
			(end 0.2794 -0.1016)
			(stroke
				(width 0.1)
				(type default)
			)
			(layer "F.Fab")
		)
		(fp_line
			(start 0.2794 -0.1016)
			(end -0.2794 -0.1016)
			(stroke
				(width 0.1)
				(type default)
			)
			(layer "F.Fab")
		)
		(fp_line
			(start -0.2794 0.9906)
			(end 0.2794 0.9906)
			(stroke
				(width 0.1)
				(type default)
			)
			(layer "F.Fab")
		)
		(fp_line
			(start -0.2794 -0.1016)
			(end -0.2794 0.9906)
			(stroke
				(width 0.1)
				(type default)
			)
			(layer "F.Fab")
		)
		(pad "1" smd rect
			(at 0 0 180)
			(size 0.508 0.508)
			(layers "F.Cu" "F.Mask" "F.Paste")
			(net "P3V3_STBY")
		)
		(pad "2" smd rect
			(at 0 0.889 180)
			(size 0.508 0.508)
			(layers "F.Cu" "F.Mask" "F.Paste")
			(net "PWRGD_PVPP_KLM_R")
		)
		(zone
			(layer "F.Cu")
			(hatch none 0.5)
			(connect_pads
				(clearance 0)
			)
			(min_thickness 0.25)
			(keepout
				(tracks not_allowed)
				(vias allowed)
				(pads allowed)
				(copperpour not_allowed)
				(footprints allowed)
			)
			(placement
				(enabled no)
				(sheetname "")
			)
			(fill
				(thermal_gap 0.5)
				(thermal_bridge_width 0.5)
				(island_removal_mode 0)
			)
			(polygon
				(pts
					(xy 180.213 -131.5085) (xy 179.705 -131.5085) (xy 179.705 -131.1275) (xy 180.213 -131.1275)
				)
			)
		)
		(zone
			(layer "F.Cu")
			(hatch none 0.5)
			(connect_pads
				(clearance 0)
			)
			(min_thickness 0.25)
			(keepout
				(tracks allowed)
				(vias not_allowed)
				(pads allowed)
				(copperpour not_allowed)
				(footprints allowed)
			)
			(placement
				(enabled no)
				(sheetname "")
			)
			(fill
				(thermal_gap 0.5)
				(thermal_bridge_width 0.5)
				(island_removal_mode 0)
			)
			(polygon
				(pts
					(xy 180.213 -131.1275) (xy 179.705 -131.1275) (xy 179.705 -131.5085) (xy 180.213 -131.5085)
				)
			)
		)
	)
	(footprint ""
		(layer "F.Cu")
		(at 277.0632 -79.6036 180)
		(property "Reference" "C6D2"
			(at 0 0 180)
			(layer "F.SilkS")
			(hide yes)
			(effects
				(font
					(size 1.27 1.27)
				)
			)
		)
		(property "Value" ""
			(at 0 0 180)
			(layer "F.Fab")
			(effects
				(font
					(size 1.27 1.27)
				)
			)
		)
		(duplicate_pad_numbers_are_jumpers no)
		(fp_poly
			(pts
				(xy -0.4953 -0.2032) (xy 0.4953 -0.2032) (xy 0.4953 1.6002) (xy -0.4953 1.6002)
			)
			(stroke
				(width 0)
				(type default)
			)
			(fill no)
			(layer "F.CrtYd")
		)
		(fp_line
			(start 0.4953 1.6002)
			(end -0.4953 1.6002)
			(stroke
				(width 0.1)
				(type default)
			)
			(layer "F.Fab")
		)
		(fp_line
			(start 0.4953 -0.2032)
			(end 0.4953 1.6002)
			(stroke
				(width 0.1)
				(type default)
			)
			(layer "F.Fab")
		)
		(fp_line
			(start -0.4953 1.6002)
			(end -0.4953 -0.2032)
			(stroke
				(width 0.1)
				(type default)
			)
			(layer "F.Fab")
		)
		(fp_line
			(start -0.4953 -0.2032)
			(end 0.4953 -0.2032)
			(stroke
				(width 0.1)
				(type default)
			)
			(layer "F.Fab")
		)
		(pad "1" smd rect
			(at 0 0 180)
			(size 0.762 0.889)
			(layers "F.Cu" "F.Mask" "F.Paste")
			(net "PVCCMCP_CPU0")
		)
		(pad "2" smd rect
			(at 0 1.397 180)
			(size 0.762 0.889)
			(layers "F.Cu" "F.Mask" "F.Paste")
			(net "GND")
		)
		(zone
			(layer "F.Cu")
			(hatch none 0.5)
			(connect_pads
				(clearance 0)
			)
			(min_thickness 0.25)
			(keepout
				(tracks not_allowed)
				(vias allowed)
				(pads allowed)
				(copperpour not_allowed)
				(footprints allowed)
			)
			(placement
				(enabled no)
				(sheetname "")
			)
			(fill
				(thermal_gap 0.5)
				(thermal_bridge_width 0.5)
				(island_removal_mode 0)
			)
			(polygon
				(pts
					(xy 277.4442 -80.0481) (xy 276.6822 -80.0481) (xy 276.6822 -80.5561) (xy 277.4442 -80.5561)
				)
			)
		)
	)
	(footprint ""
		(layer "F.Cu")
		(at 281.01036 -81.96072 90)
		(property "Reference" "R6D16"
			(at 0 0 90)
			(layer "F.SilkS")
			(hide yes)
			(effects
				(font
					(size 1.27 1.27)
				)
			)
		)
		(property "Value" ""
			(at 0 0 90)
			(layer "F.Fab")
			(effects
				(font
					(size 1.27 1.27)
				)
			)
		)
		(duplicate_pad_numbers_are_jumpers no)
		(fp_poly
			(pts
				(xy -0.2794 -0.1016) (xy 0.2794 -0.1016) (xy 0.2794 0.9906) (xy -0.2794 0.9906)
			)
			(stroke
				(width 0)
				(type default)
			)
			(fill no)
			(layer "F.CrtYd")
		)
		(fp_line
			(start 0.2794 -0.1016)
			(end -0.2794 -0.1016)
			(stroke
				(width 0.1)
				(type default)
			)
			(layer "F.Fab")
		)
		(fp_line
			(start -0.2794 -0.1016)
			(end -0.2794 0.9906)
			(stroke
				(width 0.1)
				(type default)
			)
			(layer "F.Fab")
		)
		(fp_line
			(start 0.2794 0.9906)
			(end 0.2794 -0.1016)
			(stroke
				(width 0.1)
				(type default)
			)
			(layer "F.Fab")
		)
		(fp_line
			(start -0.2794 0.9906)
			(end 0.2794 0.9906)
			(stroke
				(width 0.1)
				(type default)
			)
			(layer "F.Fab")
		)
		(pad "1" smd rect
			(at 0 0 90)
			(size 0.508 0.508)
			(layers "F.Cu" "F.Mask" "F.Paste")
			(net "FM_CPU_BMC_INIT")
		)
		(pad "2" smd rect
			(at 0 0.889 90)
			(size 0.508 0.508)
			(layers "F.Cu" "F.Mask" "F.Paste")
			(net "H_CPU0_BMCINIT")
		)
		(zone
			(layer "F.Cu")
			(hatch none 0.5)
			(connect_pads
				(clearance 0)
			)
			(min_thickness 0.25)
			(keepout
				(tracks allowed)
				(vias not_allowed)
				(pads allowed)
				(copperpour not_allowed)
				(footprints allowed)
			)
			(placement
				(enabled no)
				(sheetname "")
			)
			(fill
				(thermal_gap 0.5)
				(thermal_bridge_width 0.5)
				(island_removal_mode 0)
			)
			(polygon
				(pts
					(xy 281.26436 -81.70672) (xy 281.26436 -82.21472) (xy 281.64536 -82.21472) (xy 281.64536 -81.70672)
				)
			)
		)
		(zone
			(layer "F.Cu")
			(hatch none 0.5)
			(connect_pads
				(clearance 0)
			)
			(min_thickness 0.25)
			(keepout
				(tracks not_allowed)
				(vias allowed)
				(pads allowed)
				(copperpour not_allowed)
				(footprints allowed)
			)
			(placement
				(enabled no)
				(sheetname "")
			)
			(fill
				(thermal_gap 0.5)
				(thermal_bridge_width 0.5)
				(island_removal_mode 0)
			)
			(polygon
				(pts
					(xy 281.64536 -81.70672) (xy 281.64536 -82.21472) (xy 281.26436 -82.21472) (xy 281.26436 -81.70672)
				)
			)
		)
	)
	(footprint ""
		(layer "F.Cu")
		(at 354.805234 -129.3622)
		(property "Reference" "R7B17"
			(at 0 0 0)
			(layer "F.SilkS")
			(hide yes)
			(effects
				(font
					(size 1.27 1.27)
				)
			)
		)
		(property "Value" ""
			(at 0 0 0)
			(layer "F.Fab")
			(effects
				(font
					(size 1.27 1.27)
				)
			)
		)
		(duplicate_pad_numbers_are_jumpers no)
		(fp_poly
			(pts
				(xy -0.2794 -0.1016) (xy 0.2794 -0.1016) (xy 0.2794 0.9906) (xy -0.2794 0.9906)
			)
			(stroke
				(width 0)
				(type default)
			)
			(fill no)
			(layer "F.CrtYd")
		)
		(fp_line
			(start -0.2794 -0.1016)
			(end -0.2794 0.9906)
			(stroke
				(width 0.1)
				(type default)
			)
			(layer "F.Fab")
		)
		(fp_line
			(start -0.2794 0.9906)
			(end 0.2794 0.9906)
			(stroke
				(width 0.1)
				(type default)
			)
			(layer "F.Fab")
		)
		(fp_line
			(start 0.2794 -0.1016)
			(end -0.2794 -0.1016)
			(stroke
				(width 0.1)
				(type default)
			)
			(layer "F.Fab")
		)
		(fp_line
			(start 0.2794 0.9906)
			(end 0.2794 -0.1016)
			(stroke
				(width 0.1)
				(type default)
			)
			(layer "F.Fab")
		)
		(pad "1" smd rect
			(at 0 0)
			(size 0.508 0.508)
			(layers "F.Cu" "F.Mask" "F.Paste")
			(net "P3V3_STBY")
		)
		(pad "2" smd rect
			(at 0 0.889)
			(size 0.508 0.508)
			(layers "F.Cu" "F.Mask" "F.Paste")
			(net "PWRGD_PVPP_DEF_R")
		)
		(zone
			(layer "F.Cu")
			(hatch none 0.5)
			(connect_pads
				(clearance 0)
			)
			(min_thickness 0.25)
			(keepout
				(tracks allowed)
				(vias not_allowed)
				(pads allowed)
				(copperpour not_allowed)
				(footprints allowed)
			)
			(placement
				(enabled no)
				(sheetname "")
			)
			(fill
				(thermal_gap 0.5)
				(thermal_bridge_width 0.5)
				(island_removal_mode 0)
			)
			(polygon
				(pts
					(xy 354.551234 -129.1082) (xy 355.059234 -129.1082) (xy 355.059234 -128.7272) (xy 354.551234 -128.7272)
				)
			)
		)
		(zone
			(layer "F.Cu")
			(hatch none 0.5)
			(connect_pads
				(clearance 0)
			)
			(min_thickness 0.25)
			(keepout
				(tracks not_allowed)
				(vias allowed)
				(pads allowed)
				(copperpour not_allowed)
				(footprints allowed)
			)
			(placement
				(enabled no)
				(sheetname "")
			)
			(fill
				(thermal_gap 0.5)
				(thermal_bridge_width 0.5)
				(island_removal_mode 0)
			)
			(polygon
				(pts
					(xy 354.551234 -128.7272) (xy 355.059234 -128.7272) (xy 355.059234 -129.1082) (xy 354.551234 -129.1082)
				)
			)
		)
	)
	(footprint ""
		(layer "F.Cu")
		(at 10.8204 -8.951976)
		(property "Reference" "L1G1"
			(at 3.378708 -4.251706 0)
			(unlocked yes)
			(layer "F.SilkS")
			(effects
				(font
					(size 0.4064 0.254)
					(thickness 0.1524)
				)
			)
		)
		(property "Value" ""
			(at 0 0 0)
			(layer "F.Fab")
			(effects
				(font
					(size 1.27 1.27)
				)
			)
		)
		(duplicate_pad_numbers_are_jumpers no)
		(fp_line
			(start -1.1303 -3.199892)
			(end 8.3693 -3.199892)
			(stroke
				(width 0.1524)
				(type default)
			)
			(layer "F.SilkS")
		)
		(fp_line
			(start -1.1303 -1.6637)
			(end -1.1303 -3.199892)
			(stroke
				(width 0.1524)
				(type default)
			)
			(layer "F.SilkS")
		)
		(fp_line
			(start -1.1303 3.199892)
			(end -1.1303 1.6637)
			(stroke
				(width 0.1524)
				(type default)
			)
			(layer "F.SilkS")
		)
		(fp_line
			(start 8.3693 -3.199892)
			(end 8.3693 -1.6637)
			(stroke
				(width 0.1524)
				(type default)
			)
			(layer "F.SilkS")
		)
		(fp_line
			(start 8.3693 1.6637)
			(end 8.3693 3.199892)
			(stroke
				(width 0.1524)
				(type default)
			)
			(layer "F.SilkS")
		)
		(fp_line
			(start 8.3693 3.199892)
			(end -1.1303 3.199892)
			(stroke
				(width 0.1524)
				(type default)
			)
			(layer "F.SilkS")
		)
		(fp_rect
			(start -1.1303 3.199892)
			(end 8.3693 -3.199892)
			(stroke
				(width 0)
				(type default)
			)
			(fill no)
			(layer "F.CrtYd")
		)
		(fp_line
			(start -1.1303 -3.199892)
			(end 8.3693 -3.199892)
			(stroke
				(width 0.1)
				(type default)
			)
			(layer "F.Fab")
		)
		(fp_line
			(start -1.1303 3.199892)
			(end -1.1303 -3.199892)
			(stroke
				(width 0.1)
				(type default)
			)
			(layer "F.Fab")
		)
		(fp_line
			(start 8.3693 -3.199892)
			(end 8.3693 3.199892)
			(stroke
				(width 0.1)
				(type default)
			)
			(layer "F.Fab")
		)
		(fp_line
			(start 8.3693 3.199892)
			(end -1.1303 3.199892)
			(stroke
				(width 0.1)
				(type default)
			)
			(layer "F.Fab")
		)
		(pad "1" smd rect
			(at 0 0)
			(size 3.683 2.667)
			(layers "F.Cu" "F.Mask" "F.Paste")
			(net "VR_PVDDQ_GHJ_PH1_SW")
		)
		(pad "2" smd rect
			(at 7.239 0)
			(size 3.683 2.667)
			(layers "F.Cu" "F.Mask" "F.Paste")
			(net "PVDDQ_GHJ")
		)
	)
	(footprint ""
		(layer "F.Cu")
		(at 14.7066 -126.6825 90)
		(property "Reference" "C1B10"
			(at 5.68833 3.1496 0)
			(unlocked yes)
			(layer "F.SilkS")
			(effects
				(font
					(size 0.7874 0.5842)
					(thickness 0.1524)
				)
				(justify left)
			)
		)
		(property "Value" ""
			(at 0 0 90)
			(layer "F.Fab")
			(effects
				(font
					(size 1.27 1.27)
				)
			)
		)
		(duplicate_pad_numbers_are_jumpers no)
		(fp_line
			(start 0.9017 -1.714246)
			(end 0.7239 -1.714246)
			(stroke
				(width 0.1524)
				(type default)
			)
			(layer "F.SilkS")
		)
		(fp_line
			(start -0.7239 -1.714246)
			(end -0.9017 -1.714246)
			(stroke
				(width 0.1524)
				(type default)
			)
			(layer "F.SilkS")
		)
		(fp_line
			(start -0.9017 -1.714246)
			(end -0.9017 1.587754)
			(stroke
				(width 0.1524)
				(type default)
			)
			(layer "F.SilkS")
		)
		(fp_line
			(start 2.638044 -0.733044)
			(end 0.9017 -0.733044)
			(stroke
				(width 0.1524)
				(type default)
			)
			(layer "F.SilkS")
		)
		(fp_line
			(start -0.9017 -0.733044)
			(end -2.638044 -0.733044)
			(stroke
				(width 0.1524)
				(type default)
			)
			(layer "F.SilkS")
		)
		(fp_line
			(start -2.638044 -0.733044)
			(end -3.400044 0.028956)
			(stroke
				(width 0.1524)
				(type default)
			)
			(layer "F.SilkS")
		)
		(fp_line
			(start 3.400044 0.028956)
			(end 2.638044 -0.733044)
			(stroke
				(width 0.1524)
				(type default)
			)
			(layer "F.SilkS")
		)
		(fp_line
			(start -3.400044 0.028956)
			(end -3.400044 6.067044)
			(stroke
				(width 0.1524)
				(type default)
			)
			(layer "F.SilkS")
		)
		(fp_line
			(start 0.9017 1.587754)
			(end 0.9017 -1.714246)
			(stroke
				(width 0.1524)
				(type default)
			)
			(layer "F.SilkS")
		)
		(fp_line
			(start 0.7239 1.587754)
			(end 0.9017 1.587754)
			(stroke
				(width 0.1524)
				(type default)
			)
			(layer "F.SilkS")
		)
		(fp_line
			(start -0.9017 1.587754)
			(end -0.7239 1.587754)
			(stroke
				(width 0.1524)
				(type default)
			)
			(layer "F.SilkS")
		)
		(fp_line
			(start 3.400044 6.067044)
			(end 3.400044 0.028956)
			(stroke
				(width 0.1524)
				(type default)
			)
			(layer "F.SilkS")
		)
		(fp_line
			(start 0.9017 6.067044)
			(end 3.400044 6.067044)
			(stroke
				(width 0.1524)
				(type default)
			)
			(layer "F.SilkS")
		)
		(fp_line
			(start -3.400044 6.067044)
			(end -0.9017 6.067044)
			(stroke
				(width 0.1524)
				(type default)
			)
			(layer "F.SilkS")
		)
		(fp_poly
			(pts
				(xy -3.400044 6.067044) (xy 3.400044 6.067044) (xy 3.400044 0.028956) (xy 2.638044 -0.733044) (xy -2.638044 -0.733044)
				(xy -3.400044 0.028956)
			)
			(stroke
				(width 0)
				(type default)
			)
			(fill no)
			(layer "F.CrtYd")
		)
		(fp_line
			(start 2.638044 -0.733044)
			(end -2.638044 -0.733044)
			(stroke
				(width 0.1)
				(type default)
			)
			(layer "F.Fab")
		)
		(fp_line
			(start -2.638044 -0.733044)
			(end -3.400044 0.028956)
			(stroke
				(width 0.1)
				(type default)
			)
			(layer "F.Fab")
		)
		(fp_line
			(start 3.400044 0.028956)
			(end 2.638044 -0.733044)
			(stroke
				(width 0.1)
				(type default)
			)
			(layer "F.Fab")
		)
		(fp_line
			(start -3.400044 0.028956)
			(end -3.400044 6.067044)
			(stroke
				(width 0.1)
				(type default)
			)
			(layer "F.Fab")
		)
		(fp_line
			(start 3.400044 6.067044)
			(end 3.400044 0.028956)
			(stroke
				(width 0.1)
				(type default)
			)
			(layer "F.Fab")
		)
		(fp_line
			(start -3.400044 6.067044)
			(end 3.400044 6.067044)
			(stroke
				(width 0.1)
				(type default)
			)
			(layer "F.Fab")
		)
		(fp_circle
			(center 0 2.667)
			(end 0 6.067044)
			(stroke
				(width 0.1)
				(type default)
			)
			(fill no)
			(layer "F.Fab")
		)
		(pad "1" smd rect
			(at 0 0 90)
			(size 0.7874 3.429)
			(layers "F.Cu" "F.Mask" "F.Paste")
			(net "VR_FET_SW_P12V_STBY_PVDDQ_KLM")
		)
		(pad "2" smd rect
			(at 0 5.334 90)
			(size 0.7874 3.429)
			(layers "F.Cu" "F.Mask" "F.Paste")
			(net "GND")
		)
	)
)
